# BASEBOARD_FAB2 (Tioga Pass) — schematic netlist excerpt (pin names and nets, part order shuffled) for the footprints in the layout excerpt that follows; sources: Cadence DE-HDL packaged netlist, KiCad conversion of Wiwynn_Tioga_Pass_MB.brd

C1M14  CAP  0.22UF 16V 10% X7R  pkg 0402  page 106 : A = P3E_CPU0_PE3_OCP_TXP<11> ; B = P3E_OCP_CPU0_PE3_C_TXP<11>
R9M7  RES  100.0 1% EMPTY  pkg 0402  page 226 : A = PVCCIO_CPU1 ; B = SVID_DIO1_CPU1_R
C9R11  CAP  10UF 16V 10% X6S  pkg 0805  page 207 : A = VR_FET_SW_P12V_STBY_PVCCIN_CPU1 ; B = GND

(kicad_pcb
	(version 20260206)
	(generator "pcbnew")
	(generator_version "10.0")
	(general
		(thickness 1.6)
		(legacy_teardrops no)
	)
	(paper "A4")
	(title_block
		(title "Wiwynn_Tioga_Pass_MB.brd")
		(comment 1 "Tioga Pass / footprints 3037-3039 of 4770")
	)
	(layers
		(0 "F.Cu" signal "TOP")
		(4 "In1.Cu" signal "L2GND")
		(6 "In2.Cu" signal "L3")
		(8 "In3.Cu" signal "L4GND")
		(10 "In4.Cu" signal "L5")
		(12 "In5.Cu" signal "L6GND")
		(14 "In6.Cu" signal "L7VCC")
		(16 "In7.Cu" signal "L8VCC")
		(18 "In8.Cu" signal "L9GND")
		(20 "In9.Cu" signal "L10")
		(22 "In10.Cu" signal "L11GND")
		(24 "In11.Cu" signal "L12")
		(26 "In12.Cu" signal "L13GND")
		(2 "B.Cu" signal "BOTTOM")
		(9 "F.Adhes" user "F.Adhesive")
		(11 "B.Adhes" user "B.Adhesive")
		(13 "F.Paste" user "Package Geometry/Pastemask Top")
		(15 "B.Paste" user "Package Geometry/Pastemask Bottom")
		(5 "F.SilkS" user "Ref Des/Silkscreen Top")
		(7 "B.SilkS" user "Ref Des/Silkscreen Bottom")
		(1 "F.Mask" user "Board Geometry/Soldermask Top")
		(3 "B.Mask" user "Board Geometry/Soldermask Bottom")
		(17 "Dwgs.User" user "User.Drawings")
		(19 "Cmts.User" user "User.Comments")
		(21 "Eco1.User" user "User.Eco1")
		(23 "Eco2.User" user "User.Eco2")
		(25 "Edge.Cuts" user "Board Geometry/Outline")
		(27 "Margin" user)
		(31 "F.CrtYd" user "Package Geometry/Place Bound Top")
		(29 "B.CrtYd" user "Package Geometry/Place Bound Bottom")
		(35 "F.Fab" user "Ref Des/Assembly Top")
		(33 "B.Fab" user "Ref Des/Assembly Bottom")
	)
	(footprint ""
		(layer "B.Cu")
		(at 453.517 -116.49202)
		(property "Reference" "C1M14"
			(at 0 0 0)
			(layer "B.SilkS")
			(hide yes)
			(effects
				(font
					(size 1.27 1.27)
				)
				(justify mirror)
			)
		)
		(property "Value" ""
			(at 0 0 0)
			(layer "B.Fab")
			(effects
				(font
					(size 1.27 1.27)
				)
				(justify mirror)
			)
		)
		(duplicate_pad_numbers_are_jumpers no)
		(fp_rect
			(start -0.3048 0.9906)
			(end 0.3048 -0.1016)
			(stroke
				(width 0)
				(type default)
			)
			(fill no)
			(layer "B.CrtYd")
		)
		(fp_line
			(start -0.3048 -0.1016)
			(end 0.3048 -0.1016)
			(stroke
				(width 0.1)
				(type default)
			)
			(layer "B.Fab")
		)
		(fp_line
			(start -0.3048 0.9906)
			(end -0.3048 -0.1016)
			(stroke
				(width 0.1)
				(type default)
			)
			(layer "B.Fab")
		)
		(fp_line
			(start 0.3048 -0.1016)
			(end 0.3048 0.9906)
			(stroke
				(width 0.1)
				(type default)
			)
			(layer "B.Fab")
		)
		(fp_line
			(start 0.3048 0.9906)
			(end -0.3048 0.9906)
			(stroke
				(width 0.1)
				(type default)
			)
			(layer "B.Fab")
		)
		(pad "1" smd rect
			(at 0 0 180)
			(size 0.508 0.508)
			(layers "B.Cu" "B.Mask" "B.Paste")
			(net "P3E_CPU0_PE3_OCP_TXP<11>")
		)
		(pad "2" smd rect
			(at 0 0.889 180)
			(size 0.508 0.508)
			(layers "B.Cu" "B.Mask" "B.Paste")
			(net "P3E_OCP_CPU0_PE3_C_TXP<11>")
		)
		(zone
			(layer "B.Cu")
			(hatch none 0.5)
			(connect_pads
				(clearance 0)
			)
			(min_thickness 0.25)
			(keepout
				(tracks allowed)
				(vias not_allowed)
				(pads allowed)
				(copperpour not_allowed)
				(footprints allowed)
			)
			(placement
				(enabled no)
				(sheetname "")
			)
			(fill
				(thermal_gap 0.5)
				(thermal_bridge_width 0.5)
				(island_removal_mode 0)
			)
			(polygon
				(pts
					(xy 453.263 -115.85702) (xy 453.771 -115.85702) (xy 453.771 -116.23802) (xy 453.263 -116.23802)
				)
			)
		)
		(zone
			(layer "B.Cu")
			(hatch none 0.5)
			(connect_pads
				(clearance 0)
			)
			(min_thickness 0.25)
			(keepout
				(tracks not_allowed)
				(vias allowed)
				(pads allowed)
				(copperpour not_allowed)
				(footprints allowed)
			)
			(placement
				(enabled no)
				(sheetname "")
			)
			(fill
				(thermal_gap 0.5)
				(thermal_bridge_width 0.5)
				(island_removal_mode 0)
			)
			(polygon
				(pts
					(xy 453.263 -115.85702) (xy 453.771 -115.85702) (xy 453.771 -116.23802) (xy 453.263 -116.23802)
				)
			)
		)
	)
	(footprint ""
		(layer "B.Cu")
		(at -2.5146 -127.7112 -90)
		(property "Reference" "R9M7"
			(at 0 0 90)
			(layer "B.SilkS")
			(hide yes)
			(effects
				(font
					(size 1.27 1.27)
				)
				(justify mirror)
			)
		)
		(property "Value" ""
			(at 0 0 90)
			(layer "B.Fab")
			(effects
				(font
					(size 1.27 1.27)
				)
				(justify mirror)
			)
		)
		(duplicate_pad_numbers_are_jumpers no)
		(fp_rect
			(start 0.2794 0.9906)
			(end -0.2794 -0.1016)
			(stroke
				(width 0)
				(type default)
			)
			(fill no)
			(layer "B.CrtYd")
		)
		(fp_line
			(start -0.2794 0.9906)
			(end -0.2794 -0.1016)
			(stroke
				(width 0.1)
				(type default)
			)
			(layer "B.Fab")
		)
		(fp_line
			(start 0.2794 0.9906)
			(end -0.2794 0.9906)
			(stroke
				(width 0.1)
				(type default)
			)
			(layer "B.Fab")
		)
		(fp_line
			(start -0.2794 -0.1016)
			(end 0.2794 -0.1016)
			(stroke
				(width 0.1)
				(type default)
			)
			(layer "B.Fab")
		)
		(fp_line
			(start 0.2794 -0.1016)
			(end 0.2794 0.9906)
			(stroke
				(width 0.1)
				(type default)
			)
			(layer "B.Fab")
		)
		(pad "1" smd rect
			(at 0 0 90)
			(size 0.508 0.508)
			(layers "B.Cu" "B.Mask" "B.Paste")
			(net "PVCCIO_CPU1")
		)
		(pad "2" smd rect
			(at 0 0.889 90)
			(size 0.508 0.508)
			(layers "B.Cu" "B.Mask" "B.Paste")
			(net "SVID_DIO1_CPU1_R")
		)
		(zone
			(layer "B.Cu")
			(hatch none 0.5)
			(connect_pads
				(clearance 0)
			)
			(min_thickness 0.25)
			(keepout
				(tracks not_allowed)
				(vias allowed)
				(pads allowed)
				(copperpour not_allowed)
				(footprints allowed)
			)
			(placement
				(enabled no)
				(sheetname "")
			)
			(fill
				(thermal_gap 0.5)
				(thermal_bridge_width 0.5)
				(island_removal_mode 0)
			)
			(polygon
				(pts
					(xy -3.1496 -127.4572) (xy -2.7686 -127.4572) (xy -2.7686 -127.9652) (xy -3.1496 -127.9652)
				)
			)
		)
		(zone
			(layer "B.Cu")
			(hatch none 0.5)
			(connect_pads
				(clearance 0)
			)
			(min_thickness 0.25)
			(keepout
				(tracks allowed)
				(vias not_allowed)
				(pads allowed)
				(copperpour not_allowed)
				(footprints allowed)
			)
			(placement
				(enabled no)
				(sheetname "")
			)
			(fill
				(thermal_gap 0.5)
				(thermal_bridge_width 0.5)
				(island_removal_mode 0)
			)
			(polygon
				(pts
					(xy -3.1496 -127.4572) (xy -2.7686 -127.4572) (xy -2.7686 -127.9652) (xy -3.1496 -127.9652)
				)
			)
		)
	)
	(footprint ""
		(layer "B.Cu")
		(at 32.832802 -56.646064 90)
		(property "Reference" "C9R11"
			(at 0 0 90)
			(layer "B.SilkS")
			(hide yes)
			(effects
				(font
					(size 1.27 1.27)
				)
				(justify mirror)
			)
		)
		(property "Value" ""
			(at 0 0 90)
			(layer "B.Fab")
			(effects
				(font
					(size 1.27 1.27)
				)
				(justify mirror)
			)
		)
		(duplicate_pad_numbers_are_jumpers no)
		(fp_poly
			(pts
				(xy 0.7239 -0.2159) (xy -0.7239 -0.2159) (xy -0.7239 1.9939) (xy 0.7239 1.9939)
			)
			(stroke
				(width 0)
				(type default)
			)
			(fill no)
			(layer "B.CrtYd")
		)
		(fp_line
			(start 0.7239 -0.2159)
			(end 0.7239 1.9939)
			(stroke
				(width 0.1)
				(type default)
			)
			(layer "B.Fab")
		)
		(fp_line
			(start -0.7239 -0.2159)
			(end 0.7239 -0.2159)
			(stroke
				(width 0.1)
				(type default)
			)
			(layer "B.Fab")
		)
		(fp_line
			(start 0.7239 1.9939)
			(end -0.7239 1.9939)
			(stroke
				(width 0.1)
				(type default)
			)
			(layer "B.Fab")
		)
		(fp_line
			(start -0.7239 1.9939)
			(end -0.7239 -0.2159)
			(stroke
				(width 0.1)
				(type default)
			)
			(layer "B.Fab")
		)
		(pad "1" smd rect
			(at 0 0 270)
			(size 1.27 1.016)
			(layers "B.Cu" "B.Mask" "B.Paste")
			(net "VR_FET_SW_P12V_STBY_PVCCIN_CPU1")
		)
		(pad "2" smd rect
			(at 0 1.778 270)
			(size 1.27 1.016)
			(layers "B.Cu" "B.Mask" "B.Paste")
			(net "GND")
		)
		(zone
			(layer "B.Cu")
			(hatch none 0.5)
			(connect_pads
				(clearance 0)
			)
			(min_thickness 0.25)
			(keepout
				(tracks not_allowed)
				(vias allowed)
				(pads allowed)
				(copperpour not_allowed)
				(footprints allowed)
			)
			(placement
				(enabled no)
				(sheetname "")
			)
			(fill
				(thermal_gap 0.5)
				(thermal_bridge_width 0.5)
				(island_removal_mode 0)
			)
			(polygon
				(pts
					(xy 33.340802 -57.281064) (xy 33.340802 -56.011064) (xy 34.102802 -56.011064) (xy 34.102802 -57.281064)
				)
			)
		)
	)
)
